(kicad_pcb
	(version 20260206)
	(generator "pcbnew")
	(generator_version "10.0")
	(general
		(thickness 1.6)
		(legacy_teardrops no)
	)
	(paper "A4")
	(title_block
		(title "panther-plus-userver — 13130-1b_20150205.brd")
		(comment 1 "Honey Badger (Wiwynn) / footprint 894 of 1509 (DIMM1), pads 44-50 of 210")
	)
	(layers
		(0 "F.Cu" signal "TOP")
		(4 "In1.Cu" signal "L2")
		(6 "In2.Cu" signal "L3")
		(8 "In3.Cu" signal "L4")
		(10 "In4.Cu" signal "L5")
		(12 "In5.Cu" signal "L6")
		(14 "In6.Cu" signal "L7")
		(16 "In7.Cu" signal "L8")
		(18 "In8.Cu" signal "L9")
		(20 "In9.Cu" signal "L10")
		(22 "In10.Cu" signal "L11")
		(2 "B.Cu" signal "BOTTOM")
		(9 "F.Adhes" user "F.Adhesive")
		(11 "B.Adhes" user "B.Adhesive")
		(13 "F.Paste" user "Package Geometry/Pastemask Top")
		(15 "B.Paste" user "Package Geometry/Pastemask Bottom")
		(5 "F.SilkS" user "Ref Des/Silkscreen Top")
		(7 "B.SilkS" user "Ref Des/Silkscreen Bottom")
		(1 "F.Mask" user "Board Geometry/Soldermask Top")
		(3 "B.Mask" user "Board Geometry/Soldermask Bottom")
		(17 "Dwgs.User" user "User.Drawings")
		(19 "Cmts.User" user "User.Comments")
		(21 "Eco1.User" user "User.Eco1")
		(23 "Eco2.User" user "User.Eco2")
		(25 "Edge.Cuts" user "Board Geometry/Outline")
		(27 "Margin" user)
		(31 "F.CrtYd" user "Package Geometry/Place Bound Top")
		(29 "B.CrtYd" user "Package Geometry/Place Bound Bottom")
		(35 "F.Fab" user "Ref Des/Assembly Top")
		(33 "B.Fab" user "Ref Des/Assembly Bottom")
	)
	(footprint ""
		(layer "B.Cu")
		(at 158.500064 -66.699892 180)
		(property "Reference" "DIMM1"
			(at 0 0 0)
			(layer "B.SilkS")
			(hide yes)
			(effects
				(font
					(size 1.27 1.27)
				)
				(justify mirror)
			)
		)
		(property "Value" "DDR3-204P-142-COLAY-1-GP-U"
			(at 41.312338 -16.676878 180)
			(unlocked yes)
			(layer "B.Fab")
			(hide yes)
			(effects
				(font
					(size 1.016 1.016)
					(thickness 0.1524)
				)
				(justify mirror)
			)
		)
		(property "Device Type" "AS0A626-J8R6-7H-COLAY-1"
			(at 41.312338 -18.200878 180)
			(unlocked yes)
			(layer "B.Fab")
			(hide yes)
			(effects
				(font
					(size 1.016 1.016)
					(thickness 0.1524)
				)
				(justify mirror)
			)
		)
		(duplicate_pad_numbers_are_jumpers no)
		(pad "42" smd custom
			(at -19.349974 4.100068)
			(size 0.1143 0.1143)
			(layers "B.Cu" "B.Mask" "B.Paste")
			(net "M_A_DQ21")
			(options
				(clearance outline)
				(anchor circle)
			)
			(primitives
				(gr_poly
					(pts
						(xy 0 -0.9017) (xy -0.03175 -0.89916) (xy -0.0635 -0.889) (xy -0.09144 -0.87376) (xy -0.11684 -0.85344)
						(xy -0.13716 -0.82804) (xy -0.1524 -0.8001) (xy -0.16256 -0.76835) (xy -0.1651 -0.7366) (xy -0.1651 0.13462)
						(xy -0.17272 0.14224) (xy -0.19812 0.1778) (xy -0.2032 0.18796) (xy -0.20701 0.19685) (xy -0.21209 0.20701)
						(xy -0.2159 0.21717) (xy -0.21844 0.22733) (xy -0.22225 0.23876) (xy -0.22352 0.24892) (xy -0.22606 0.25908)
						(xy -0.22733 0.27051) (xy -0.22733 0.28067) (xy -0.2286 0.2921) (xy -0.22733 0.30353) (xy -0.22733 0.31369)
						(xy -0.22606 0.32512) (xy -0.22352 0.33528) (xy -0.22225 0.34544) (xy -0.21844 0.35687) (xy -0.2159 0.36703)
						(xy -0.21209 0.37719) (xy -0.20701 0.38735) (xy -0.2032 0.39624) (xy -0.19812 0.4064) (xy -0.17272 0.44196)
						(xy -0.1651 0.44958) (xy -0.1651 0.7366) (xy -0.16256 0.76835) (xy -0.1524 0.8001) (xy -0.13716 0.82804)
						(xy -0.11684 0.85344) (xy -0.09144 0.87376) (xy -0.0635 0.889) (xy -0.03175 0.89916) (xy 0 0.9017)
						(xy 0.03175 0.89916) (xy 0.0635 0.889) (xy 0.09144 0.87376) (xy 0.11684 0.85344) (xy 0.13716 0.82804)
						(xy 0.1524 0.8001) (xy 0.16256 0.76835) (xy 0.1651 0.7366) (xy 0.1651 0.44958) (xy 0.17272 0.44196)
						(xy 0.19812 0.4064) (xy 0.2032 0.39624) (xy 0.20701 0.38735) (xy 0.21209 0.37719) (xy 0.2159 0.36703)
						(xy 0.21844 0.35687) (xy 0.22225 0.34544) (xy 0.22352 0.33528) (xy 0.22606 0.32512) (xy 0.22733 0.31369)
						(xy 0.22733 0.30353) (xy 0.2286 0.2921) (xy 0.22733 0.28067) (xy 0.22733 0.27051) (xy 0.22606 0.25908)
						(xy 0.22352 0.24892) (xy 0.22225 0.23876) (xy 0.21844 0.22733) (xy 0.2159 0.21717) (xy 0.21209 0.20701)
						(xy 0.20701 0.19685) (xy 0.2032 0.18796) (xy 0.19812 0.1778) (xy 0.17272 0.14224) (xy 0.1651 0.13462)
						(xy 0.1651 -0.7366) (xy 0.16256 -0.76835) (xy 0.1524 -0.8001) (xy 0.13716 -0.82804) (xy 0.11684 -0.85344)
						(xy 0.09144 -0.87376) (xy 0.0635 -0.889) (xy 0.03175 -0.89916)
					)
					(width 0)
					(fill yes)
				)
			)
		)
		(pad "43" smd custom
			(at -19.05 -4.100068)
			(size 0.1143 0.1143)
			(layers "B.Cu" "B.Mask" "B.Paste")
			(net "M_A_DQS_DN2")
			(options
				(clearance outline)
				(anchor circle)
			)
			(primitives
				(gr_poly
					(pts
						(xy 0 -0.9017) (xy -0.03175 -0.89916) (xy -0.0635 -0.889) (xy -0.09144 -0.87376) (xy -0.11684 -0.85344)
						(xy -0.13716 -0.82804) (xy -0.1524 -0.8001) (xy -0.16256 -0.76835) (xy -0.1651 -0.7366) (xy -0.1651 -0.19685)
						(xy -0.17272 -0.18923) (xy -0.17907 -0.18034) (xy -0.18669 -0.17145) (xy -0.19177 -0.16256) (xy -0.19812 -0.15367)
						(xy -0.20828 -0.13335) (xy -0.21971 -0.10287) (xy -0.22225 -0.09271) (xy -0.22479 -0.08128) (xy -0.22606 -0.07112)
						(xy -0.2286 -0.05969) (xy -0.2286 -0.01651) (xy -0.22606 -0.00508) (xy -0.22479 0.00508) (xy -0.22225 0.01651)
						(xy -0.21971 0.02667) (xy -0.20828 0.05715) (xy -0.19812 0.07747) (xy -0.19177 0.08636) (xy -0.18669 0.09525)
						(xy -0.17907 0.10414) (xy -0.17272 0.11303) (xy -0.1651 0.12065) (xy -0.1651 0.7366) (xy -0.16256 0.76835)
						(xy -0.1524 0.8001) (xy -0.13716 0.82804) (xy -0.11684 0.85344) (xy -0.09144 0.87376) (xy -0.0635 0.889)
						(xy -0.03175 0.89916) (xy 0 0.9017) (xy 0.03175 0.89916) (xy 0.0635 0.889) (xy 0.09144 0.87376)
						(xy 0.11684 0.85344) (xy 0.13716 0.82804) (xy 0.1524 0.8001) (xy 0.16256 0.76835) (xy 0.1651 0.7366)
						(xy 0.1651 0.11938) (xy 0.17272 0.11176) (xy 0.19812 0.0762) (xy 0.2032 0.06604) (xy 0.20701 0.05715)
						(xy 0.21209 0.04699) (xy 0.2159 0.03683) (xy 0.21844 0.02667) (xy 0.22225 0.01524) (xy 0.22352 0.00508)
						(xy 0.22606 -0.00508) (xy 0.22733 -0.01651) (xy 0.22733 -0.02667) (xy 0.2286 -0.0381) (xy 0.22733 -0.04953)
						(xy 0.22733 -0.05969) (xy 0.22606 -0.07112) (xy 0.22352 -0.08128) (xy 0.22225 -0.09144) (xy 0.21844 -0.10287)
						(xy 0.2159 -0.11303) (xy 0.21209 -0.12319) (xy 0.20701 -0.13335) (xy 0.2032 -0.14224) (xy 0.19812 -0.1524)
						(xy 0.17272 -0.18796) (xy 0.1651 -0.19558) (xy 0.1651 -0.7366) (xy 0.16256 -0.76835) (xy 0.1524 -0.8001)
						(xy 0.13716 -0.82804) (xy 0.11684 -0.85344) (xy 0.09144 -0.87376) (xy 0.0635 -0.889) (xy 0.03175 -0.89916)
					)
					(width 0)
					(fill yes)
				)
			)
		)
		(pad "44" smd custom
			(at -18.750026 4.100068)
			(size 0.1143 0.1143)
			(layers "B.Cu" "B.Mask" "B.Paste")
			(net "GND")
			(options
				(clearance outline)
				(anchor circle)
			)
			(primitives
				(gr_poly
					(pts
						(xy 0 -0.9017) (xy -0.03175 -0.89916) (xy -0.0635 -0.889) (xy -0.09144 -0.87376) (xy -0.11684 -0.85344)
						(xy -0.13716 -0.82804) (xy -0.1524 -0.8001) (xy -0.16256 -0.76835) (xy -0.1651 -0.7366) (xy -0.1651 -0.11938)
						(xy -0.17272 -0.11176) (xy -0.19812 -0.0762) (xy -0.2032 -0.06604) (xy -0.20701 -0.05715) (xy -0.21209 -0.04699)
						(xy -0.2159 -0.03683) (xy -0.21844 -0.02667) (xy -0.22225 -0.01524) (xy -0.22352 -0.00508) (xy -0.22606 0.00508)
						(xy -0.22733 0.01651) (xy -0.22733 0.02667) (xy -0.2286 0.0381) (xy -0.22733 0.04953) (xy -0.22733 0.05969)
						(xy -0.22606 0.07112) (xy -0.22352 0.08128) (xy -0.22225 0.09144) (xy -0.21844 0.10287) (xy -0.2159 0.11303)
						(xy -0.21209 0.12319) (xy -0.20701 0.13335) (xy -0.2032 0.14224) (xy -0.19812 0.1524) (xy -0.17272 0.18796)
						(xy -0.1651 0.19558) (xy -0.1651 0.7366) (xy -0.16256 0.76835) (xy -0.1524 0.8001) (xy -0.13716 0.82804)
						(xy -0.11684 0.85344) (xy -0.09144 0.87376) (xy -0.0635 0.889) (xy -0.03175 0.89916) (xy 0 0.9017)
						(xy 0.03175 0.89916) (xy 0.0635 0.889) (xy 0.09144 0.87376) (xy 0.11684 0.85344) (xy 0.13716 0.82804)
						(xy 0.1524 0.8001) (xy 0.16256 0.76835) (xy 0.1651 0.7366) (xy 0.1651 0.19685) (xy 0.17272 0.18923)
						(xy 0.17907 0.18034) (xy 0.18669 0.17145) (xy 0.19177 0.16256) (xy 0.19812 0.15367) (xy 0.20828 0.13335)
						(xy 0.21971 0.10287) (xy 0.22225 0.09271) (xy 0.22479 0.08128) (xy 0.22606 0.07112) (xy 0.2286 0.05969)
						(xy 0.2286 0.01651) (xy 0.22606 0.00508) (xy 0.22479 -0.00508) (xy 0.22225 -0.01651) (xy 0.21971 -0.02667)
						(xy 0.20828 -0.05715) (xy 0.19812 -0.07747) (xy 0.19177 -0.08636) (xy 0.18669 -0.09525) (xy 0.17907 -0.10414)
						(xy 0.17272 -0.11303) (xy 0.1651 -0.12065) (xy 0.1651 -0.7366) (xy 0.16256 -0.76835) (xy 0.1524 -0.8001)
						(xy 0.13716 -0.82804) (xy 0.11684 -0.85344) (xy 0.09144 -0.87376) (xy 0.0635 -0.889) (xy 0.03175 -0.89916)
					)
					(width 0)
					(fill yes)
				)
			)
		)
		(pad "45" smd custom
			(at -18.450052 -4.100068)
			(size 0.1143 0.1143)
			(layers "B.Cu" "B.Mask" "B.Paste")
			(net "M_A_DQS_DP2")
			(options
				(clearance outline)
				(anchor circle)
			)
			(primitives
				(gr_poly
					(pts
						(xy 0 -0.9017) (xy -0.03175 -0.89916) (xy -0.0635 -0.889) (xy -0.09144 -0.87376) (xy -0.11684 -0.85344)
						(xy -0.13716 -0.82804) (xy -0.1524 -0.8001) (xy -0.16256 -0.76835) (xy -0.1651 -0.7366) (xy -0.1651 -0.44958)
						(xy -0.17272 -0.44196) (xy -0.19812 -0.4064) (xy -0.2032 -0.39624) (xy -0.20701 -0.38735) (xy -0.21209 -0.37719)
						(xy -0.2159 -0.36703) (xy -0.21844 -0.35687) (xy -0.22225 -0.34544) (xy -0.22352 -0.33528) (xy -0.22606 -0.32512)
						(xy -0.22733 -0.31369) (xy -0.22733 -0.30353) (xy -0.2286 -0.2921) (xy -0.22733 -0.28067) (xy -0.22733 -0.27051)
						(xy -0.22606 -0.25908) (xy -0.22352 -0.24892) (xy -0.22225 -0.23876) (xy -0.21844 -0.22733) (xy -0.2159 -0.21717)
						(xy -0.21209 -0.20701) (xy -0.20701 -0.19685) (xy -0.2032 -0.18796) (xy -0.19812 -0.1778) (xy -0.17272 -0.14224)
						(xy -0.1651 -0.13462) (xy -0.1651 0.7366) (xy -0.16256 0.76835) (xy -0.1524 0.8001) (xy -0.13716 0.82804)
						(xy -0.11684 0.85344) (xy -0.09144 0.87376) (xy -0.0635 0.889) (xy -0.03175 0.89916) (xy 0 0.9017)
						(xy 0.03175 0.89916) (xy 0.0635 0.889) (xy 0.09144 0.87376) (xy 0.11684 0.85344) (xy 0.13716 0.82804)
						(xy 0.1524 0.8001) (xy 0.16256 0.76835) (xy 0.1651 0.7366) (xy 0.1651 -0.13462) (xy 0.17272 -0.14224)
						(xy 0.19812 -0.1778) (xy 0.2032 -0.18796) (xy 0.20701 -0.19685) (xy 0.21209 -0.20701) (xy 0.2159 -0.21717)
						(xy 0.21844 -0.22733) (xy 0.22225 -0.23876) (xy 0.22352 -0.24892) (xy 0.22606 -0.25908) (xy 0.22733 -0.27051)
						(xy 0.22733 -0.28067) (xy 0.2286 -0.2921) (xy 0.22733 -0.30353) (xy 0.22733 -0.31369) (xy 0.22606 -0.32512)
						(xy 0.22352 -0.33528) (xy 0.22225 -0.34544) (xy 0.21844 -0.35687) (xy 0.2159 -0.36703) (xy 0.21209 -0.37719)
						(xy 0.20701 -0.38735) (xy 0.2032 -0.39624) (xy 0.19812 -0.4064) (xy 0.17272 -0.44196) (xy 0.1651 -0.44958)
						(xy 0.1651 -0.7366) (xy 0.16256 -0.76835) (xy 0.1524 -0.8001) (xy 0.13716 -0.82804) (xy 0.11684 -0.85344)
						(xy 0.09144 -0.87376) (xy 0.0635 -0.889) (xy 0.03175 -0.89916)
					)
					(width 0)
					(fill yes)
				)
			)
		)
		(pad "46" smd custom
			(at -18.150078 4.100068)
			(size 0.1143 0.1143)
			(layers "B.Cu" "B.Mask" "B.Paste")
			(net "GND")
			(options
				(clearance outline)
				(anchor circle)
			)
			(primitives
				(gr_poly
					(pts
						(xy 0 -0.9017) (xy -0.03175 -0.89916) (xy -0.0635 -0.889) (xy -0.09144 -0.87376) (xy -0.11684 -0.85344)
						(xy -0.13716 -0.82804) (xy -0.1524 -0.8001) (xy -0.16256 -0.76835) (xy -0.1651 -0.7366) (xy -0.1651 0.13462)
						(xy -0.17272 0.14224) (xy -0.19812 0.1778) (xy -0.2032 0.18796) (xy -0.20701 0.19685) (xy -0.21209 0.20701)
						(xy -0.2159 0.21717) (xy -0.21844 0.22733) (xy -0.22225 0.23876) (xy -0.22352 0.24892) (xy -0.22606 0.25908)
						(xy -0.22733 0.27051) (xy -0.22733 0.28067) (xy -0.2286 0.2921) (xy -0.22733 0.30353) (xy -0.22733 0.31369)
						(xy -0.22606 0.32512) (xy -0.22352 0.33528) (xy -0.22225 0.34544) (xy -0.21844 0.35687) (xy -0.2159 0.36703)
						(xy -0.21209 0.37719) (xy -0.20701 0.38735) (xy -0.2032 0.39624) (xy -0.19812 0.4064) (xy -0.17272 0.44196)
						(xy -0.1651 0.44958) (xy -0.1651 0.7366) (xy -0.16256 0.76835) (xy -0.1524 0.8001) (xy -0.13716 0.82804)
						(xy -0.11684 0.85344) (xy -0.09144 0.87376) (xy -0.0635 0.889) (xy -0.03175 0.89916) (xy 0 0.9017)
						(xy 0.03175 0.89916) (xy 0.0635 0.889) (xy 0.09144 0.87376) (xy 0.11684 0.85344) (xy 0.13716 0.82804)
						(xy 0.1524 0.8001) (xy 0.16256 0.76835) (xy 0.1651 0.7366) (xy 0.1651 0.44958) (xy 0.17272 0.44196)
						(xy 0.19812 0.4064) (xy 0.2032 0.39624) (xy 0.20701 0.38735) (xy 0.21209 0.37719) (xy 0.2159 0.36703)
						(xy 0.21844 0.35687) (xy 0.22225 0.34544) (xy 0.22352 0.33528) (xy 0.22606 0.32512) (xy 0.22733 0.31369)
						(xy 0.22733 0.30353) (xy 0.2286 0.2921) (xy 0.22733 0.28067) (xy 0.22733 0.27051) (xy 0.22606 0.25908)
						(xy 0.22352 0.24892) (xy 0.22225 0.23876) (xy 0.21844 0.22733) (xy 0.2159 0.21717) (xy 0.21209 0.20701)
						(xy 0.20701 0.19685) (xy 0.2032 0.18796) (xy 0.19812 0.1778) (xy 0.17272 0.14224) (xy 0.1651 0.13462)
						(xy 0.1651 -0.7366) (xy 0.16256 -0.76835) (xy 0.1524 -0.8001) (xy 0.13716 -0.82804) (xy 0.11684 -0.85344)
						(xy 0.09144 -0.87376) (xy 0.0635 -0.889) (xy 0.03175 -0.89916)
					)
					(width 0)
					(fill yes)
				)
			)
		)
		(pad "47" smd custom
			(at -17.850104 -4.100068)
			(size 0.1143 0.1143)
			(layers "B.Cu" "B.Mask" "B.Paste")
			(net "GND")
			(options
				(clearance outline)
				(anchor circle)
			)
			(primitives
				(gr_poly
					(pts
						(xy 0 -0.9017) (xy -0.03175 -0.89916) (xy -0.0635 -0.889) (xy -0.09144 -0.87376) (xy -0.11684 -0.85344)
						(xy -0.13716 -0.82804) (xy -0.1524 -0.8001) (xy -0.16256 -0.76835) (xy -0.1651 -0.7366) (xy -0.1651 -0.19685)
						(xy -0.17272 -0.18923) (xy -0.17907 -0.18034) (xy -0.18669 -0.17145) (xy -0.19177 -0.16256) (xy -0.19812 -0.15367)
						(xy -0.20828 -0.13335) (xy -0.21971 -0.10287) (xy -0.22225 -0.09271) (xy -0.22479 -0.08128) (xy -0.22606 -0.07112)
						(xy -0.2286 -0.05969) (xy -0.2286 -0.01651) (xy -0.22606 -0.00508) (xy -0.22479 0.00508) (xy -0.22225 0.01651)
						(xy -0.21971 0.02667) (xy -0.20828 0.05715) (xy -0.19812 0.07747) (xy -0.19177 0.08636) (xy -0.18669 0.09525)
						(xy -0.17907 0.10414) (xy -0.17272 0.11303) (xy -0.1651 0.12065) (xy -0.1651 0.7366) (xy -0.16256 0.76835)
						(xy -0.1524 0.8001) (xy -0.13716 0.82804) (xy -0.11684 0.85344) (xy -0.09144 0.87376) (xy -0.0635 0.889)
						(xy -0.03175 0.89916) (xy 0 0.9017) (xy 0.03175 0.89916) (xy 0.0635 0.889) (xy 0.09144 0.87376)
						(xy 0.11684 0.85344) (xy 0.13716 0.82804) (xy 0.1524 0.8001) (xy 0.16256 0.76835) (xy 0.1651 0.7366)
						(xy 0.1651 0.11938) (xy 0.17272 0.11176) (xy 0.19812 0.0762) (xy 0.2032 0.06604) (xy 0.20701 0.05715)
						(xy 0.21209 0.04699) (xy 0.2159 0.03683) (xy 0.21844 0.02667) (xy 0.22225 0.01524) (xy 0.22352 0.00508)
						(xy 0.22606 -0.00508) (xy 0.22733 -0.01651) (xy 0.22733 -0.02667) (xy 0.2286 -0.0381) (xy 0.22733 -0.04953)
						(xy 0.22733 -0.05969) (xy 0.22606 -0.07112) (xy 0.22352 -0.08128) (xy 0.22225 -0.09144) (xy 0.21844 -0.10287)
						(xy 0.2159 -0.11303) (xy 0.21209 -0.12319) (xy 0.20701 -0.13335) (xy 0.2032 -0.14224) (xy 0.19812 -0.1524)
						(xy 0.17272 -0.18796) (xy 0.1651 -0.19558) (xy 0.1651 -0.7366) (xy 0.16256 -0.76835) (xy 0.1524 -0.8001)
						(xy 0.13716 -0.82804) (xy 0.11684 -0.85344) (xy 0.09144 -0.87376) (xy 0.0635 -0.889) (xy 0.03175 -0.89916)
					)
					(width 0)
					(fill yes)
				)
			)
		)
		(pad "48" smd custom
			(at -17.549876 4.100068)
			(size 0.1143 0.1143)
			(layers "B.Cu" "B.Mask" "B.Paste")
			(net "M_A_DQ22")
			(options
				(clearance outline)
				(anchor circle)
			)
			(primitives
				(gr_poly
					(pts
						(xy 0 -0.9017) (xy -0.03175 -0.89916) (xy -0.0635 -0.889) (xy -0.09144 -0.87376) (xy -0.11684 -0.85344)
						(xy -0.13716 -0.82804) (xy -0.1524 -0.8001) (xy -0.16256 -0.76835) (xy -0.1651 -0.7366) (xy -0.1651 -0.11938)
						(xy -0.17272 -0.11176) (xy -0.19812 -0.0762) (xy -0.2032 -0.06604) (xy -0.20701 -0.05715) (xy -0.21209 -0.04699)
						(xy -0.2159 -0.03683) (xy -0.21844 -0.02667) (xy -0.22225 -0.01524) (xy -0.22352 -0.00508) (xy -0.22606 0.00508)
						(xy -0.22733 0.01651) (xy -0.22733 0.02667) (xy -0.2286 0.0381) (xy -0.22733 0.04953) (xy -0.22733 0.05969)
						(xy -0.22606 0.07112) (xy -0.22352 0.08128) (xy -0.22225 0.09144) (xy -0.21844 0.10287) (xy -0.2159 0.11303)
						(xy -0.21209 0.12319) (xy -0.20701 0.13335) (xy -0.2032 0.14224) (xy -0.19812 0.1524) (xy -0.17272 0.18796)
						(xy -0.1651 0.19558) (xy -0.1651 0.7366) (xy -0.16256 0.76835) (xy -0.1524 0.8001) (xy -0.13716 0.82804)
						(xy -0.11684 0.85344) (xy -0.09144 0.87376) (xy -0.0635 0.889) (xy -0.03175 0.89916) (xy 0 0.9017)
						(xy 0.03175 0.89916) (xy 0.0635 0.889) (xy 0.09144 0.87376) (xy 0.11684 0.85344) (xy 0.13716 0.82804)
						(xy 0.1524 0.8001) (xy 0.16256 0.76835) (xy 0.1651 0.7366) (xy 0.1651 0.19685) (xy 0.17272 0.18923)
						(xy 0.17907 0.18034) (xy 0.18669 0.17145) (xy 0.19177 0.16256) (xy 0.19812 0.15367) (xy 0.20828 0.13335)
						(xy 0.21971 0.10287) (xy 0.22225 0.09271) (xy 0.22479 0.08128) (xy 0.22606 0.07112) (xy 0.2286 0.05969)
						(xy 0.2286 0.01651) (xy 0.22606 0.00508) (xy 0.22479 -0.00508) (xy 0.22225 -0.01651) (xy 0.21971 -0.02667)
						(xy 0.20828 -0.05715) (xy 0.19812 -0.07747) (xy 0.19177 -0.08636) (xy 0.18669 -0.09525) (xy 0.17907 -0.10414)
						(xy 0.17272 -0.11303) (xy 0.1651 -0.12065) (xy 0.1651 -0.7366) (xy 0.16256 -0.76835) (xy 0.1524 -0.8001)
						(xy 0.13716 -0.82804) (xy 0.11684 -0.85344) (xy 0.09144 -0.87376) (xy 0.0635 -0.889) (xy 0.03175 -0.89916)
					)
					(width 0)
					(fill yes)
				)
			)
		)
	)
)
